# TIMECARD (Time Appliance Project (Time Card)) — schematic netlist excerpt (pin names and nets, part order shuffled) for the footprints in the layout excerpt that follows; sources: Cadence DE-HDL packaged netlist, KiCad conversion of R4006-B0001-02_R01.brd

Y4  OSC6P_V2  pkg SMC_Y6_197X276  page 15
  OE  = CLK_125M_OE
  NC  = NC
  GND  = SG
  OUT_P  = OSC_125M_CLKP
  OUT_N  = OSC_125M_CLKN
  VDD  = VDD3V3_OSC_125M

(kicad_pcb
	(version 20260206)
	(generator "pcbnew")
	(generator_version "10.0")
	(general
		(thickness 1.6)
		(legacy_teardrops no)
	)
	(paper "A4")
	(title_block
		(title "timecard-production-celestica-r4006 — R4006-B0001-02_R01.brd")
		(comment 1 "Time Appliance Project (Time Card) / footprints 524-524 of 1113")
	)
	(layers
		(0 "F.Cu" signal "TOP")
		(4 "In1.Cu" signal "L02_GND1")
		(6 "In2.Cu" signal "L03_SIG1")
		(8 "In3.Cu" signal "L04_GND2")
		(10 "In4.Cu" signal "L05_VCC1")
		(12 "In5.Cu" signal "L06_VCC2")
		(14 "In6.Cu" signal "L07_GND3")
		(16 "In7.Cu" signal "L08_SIG2")
		(18 "In8.Cu" signal "L09_GND4")
		(2 "B.Cu" signal "BOTTOM")
		(9 "F.Adhes" user "F.Adhesive")
		(11 "B.Adhes" user "B.Adhesive")
		(13 "F.Paste" user "Package Geometry/Pastemask Top")
		(15 "B.Paste" user "Package Geometry/Pastemask Bottom")
		(5 "F.SilkS" user "Ref Des/Silkscreen Top")
		(7 "B.SilkS" user "Ref Des/Silkscreen Bottom")
		(1 "F.Mask" user "Board Geometry/Soldermask Top")
		(3 "B.Mask" user "Board Geometry/Soldermask Bottom")
		(17 "Dwgs.User" user "User.Drawings")
		(19 "Cmts.User" user "User.Comments")
		(21 "Eco1.User" user "User.Eco1")
		(23 "Eco2.User" user "User.Eco2")
		(25 "Edge.Cuts" user "Board Geometry/Outline")
		(27 "Margin" user)
		(31 "F.CrtYd" user "Package Geometry/Place Bound Top")
		(29 "B.CrtYd" user "Package Geometry/Place Bound Bottom")
		(35 "F.Fab" user "Ref Des/Assembly Top")
		(33 "B.Fab" user "Ref Des/Assembly Bottom")
	)
	(footprint ""
		(layer "F.Cu")
		(at 101.092 -20.955 90)
		(property "Reference" "Y4"
			(at -3.83667 -0.762 0)
			(unlocked yes)
			(layer "F.SilkS")
			(effects
				(font
					(size 0.7874 0.5842)
					(thickness 0.1524)
				)
			)
		)
		(property "Value" ""
			(at 0 0 90)
			(layer "F.Fab")
			(effects
				(font
					(size 1.27 1.27)
				)
			)
		)
		(property "User Part Number" "PARTNUM*"
			(at 0 6.106668 90)
			(unlocked yes)
			(layer "Cmts.User")
			(hide yes)
			(effects
				(font
					(size 0.7874 0.5842)
					(thickness 0.1524)
				)
			)
		)
		(property "Device Type" "OSC6P_V2-A130-00004-AW"
			(at 0 4.912868 90)
			(unlocked yes)
			(layer "F.Fab")
			(hide yes)
			(effects
				(font
					(size 0.7874 0.5842)
					(thickness 0.1524)
				)
			)
		)
		(duplicate_pad_numbers_are_jumpers no)
		(fp_line
			(start 2.803906 -3.803904)
			(end 2.803906 3.803904)
			(stroke
				(width 0.1)
				(type default)
			)
			(layer "F.SilkS")
		)
		(fp_line
			(start -2.803906 -3.803904)
			(end 2.803906 -3.803904)
			(stroke
				(width 0.1)
				(type default)
			)
			(layer "F.SilkS")
		)
		(fp_line
			(start 2.803906 3.803904)
			(end -2.803906 3.803904)
			(stroke
				(width 0.1)
				(type default)
			)
			(layer "F.SilkS")
		)
		(fp_line
			(start -2.803906 3.803904)
			(end -2.803906 -3.803904)
			(stroke
				(width 0.1)
				(type default)
			)
			(layer "F.SilkS")
		)
		(fp_rect
			(start -3.057906 -4.057904)
			(end 3.057906 4.057904)
			(stroke
				(width 0)
				(type default)
			)
			(fill no)
			(layer "F.CrtYd")
		)
		(fp_line
			(start 2.549906 -3.549904)
			(end 2.549906 3.549904)
			(stroke
				(width 0.1)
				(type default)
			)
			(layer "F.Fab")
		)
		(fp_line
			(start -2.549906 -3.549904)
			(end 2.549906 -3.549904)
			(stroke
				(width 0.1)
				(type default)
			)
			(layer "F.Fab")
		)
		(fp_line
			(start 2.549906 3.549904)
			(end -2.549906 3.549904)
			(stroke
				(width 0.1)
				(type default)
			)
			(layer "F.Fab")
		)
		(fp_line
			(start -2.549906 3.549904)
			(end -2.549906 -3.549904)
			(stroke
				(width 0.1)
				(type default)
			)
			(layer "F.Fab")
		)
		(fp_text user "1"
			(at -3.480562 -2.712212 90)
			(unlocked yes)
			(layer "F.SilkS")
			(effects
				(font
					(size 0.7874 0.5842)
					(thickness 0.1524)
				)
			)
		)
		(fp_text user "3"
			(at -3.584194 2.45237 90)
			(unlocked yes)
			(layer "F.SilkS")
			(effects
				(font
					(size 0.7874 0.5842)
					(thickness 0.1524)
				)
			)
		)
		(fp_text user "6"
			(at 2.13233 -4.064 0)
			(unlocked yes)
			(layer "F.Fab")
			(effects
				(font
					(size 0.7874 0.5842)
					(thickness 0.1524)
				)
			)
		)
		(fp_text user "1"
			(at -3.253232 -2.611882 0)
			(unlocked yes)
			(layer "F.Fab")
			(effects
				(font
					(size 0.7874 0.5842)
					(thickness 0.1524)
				)
			)
		)
		(fp_text user "3"
			(at -3.356864 2.5527 0)
			(unlocked yes)
			(layer "F.Fab")
			(effects
				(font
					(size 0.7874 0.5842)
					(thickness 0.1524)
				)
			)
		)
		(fp_text user "4"
			(at 1.87833 3.937 0)
			(unlocked yes)
			(layer "F.Fab")
			(effects
				(font
					(size 0.7874 0.5842)
					(thickness 0.1524)
				)
			)
		)
		(pad "1" smd rect
			(at -1.849882 -2.54 90)
			(size 0.9906 1.397)
			(layers "F.Cu" "F.Mask" "F.Paste")
			(net "CLK_125M_OE")
		)
		(pad "2" smd rect
			(at -1.849882 0 90)
			(size 0.9906 1.397)
			(layers "F.Cu" "F.Mask" "F.Paste")
			(net "Net_762")
		)
		(pad "3" smd rect
			(at -1.849882 2.54 90)
			(size 0.9906 1.397)
			(layers "F.Cu" "F.Mask" "F.Paste")
			(net "SG")
		)
		(pad "4" smd rect
			(at 1.849882 2.54 90)
			(size 0.9906 1.397)
			(layers "F.Cu" "F.Mask" "F.Paste")
			(net "OSC_125M_CLKP")
		)
		(pad "5" smd rect
			(at 1.849882 0 90)
			(size 0.9906 1.397)
			(layers "F.Cu" "F.Mask" "F.Paste")
			(net "OSC_125M_CLKN")
		)
		(pad "6" smd rect
			(at 1.849882 -2.54 90)
			(size 0.9906 1.397)
			(layers "F.Cu" "F.Mask" "F.Paste")
			(net "VDD3V3_OSC_125M")
		)
		(zone
			(layer "F.Cu")
			(hatch none 0.5)
			(connect_pads
				(clearance 0)
			)
			(min_thickness 0.25)
			(keepout
				(tracks allowed)
				(vias not_allowed)
				(pads allowed)
				(copperpour not_allowed)
				(footprints allowed)
			)
			(placement
				(enabled no)
				(sheetname "")
			)
			(fill
				(thermal_gap 0.5)
				(thermal_bridge_width 0.5)
				(island_removal_mode 0)
			)
			(polygon
				(pts
					(xy 97.542096 -18.405094) (xy 104.641904 -18.405094) (xy 104.641904 -23.504906) (xy 97.542096 -23.504906)
				)
			)
			(polygon
				(pts
					(xy 99.2505 -19.600418) (xy 99.2505 -18.609818) (xy 97.8535 -18.609818) (xy 97.8535 -19.600418)
				)
			)
			(polygon
				(pts
					(xy 99.2505 -23.300182) (xy 99.2505 -22.309582) (xy 97.8535 -22.309582) (xy 97.8535 -23.300182)
				)
			)
			(polygon
				(pts
					(xy 101.7905 -19.600418) (xy 101.7905 -18.609818) (xy 100.3935 -18.609818) (xy 100.3935 -19.600418)
				)
			)
			(polygon
				(pts
					(xy 101.7905 -23.300182) (xy 101.7905 -22.309582) (xy 100.3935 -22.309582) (xy 100.3935 -23.300182)
				)
			)
			(polygon
				(pts
					(xy 104.3305 -19.600418) (xy 104.3305 -18.609818) (xy 102.9335 -18.609818) (xy 102.9335 -19.600418)
				)
			)
			(polygon
				(pts
					(xy 104.3305 -23.300182) (xy 104.3305 -22.309582) (xy 102.9335 -22.309582) (xy 102.9335 -23.300182)
				)
			)
		)
	)
)
